FILE_TYPE = CONNECTIVITY;
{Allegro Design Entry HDL 16.6-p007 (v16-6-112F) 10/10/2012}
"PAGE_NUMBER" = 109;
0"NC";
1"P3E_CPU0_PE1_SS_C_TXN<7:0>";
2"P3E_CPU0_PE2_SS_C_TXP<7:0>";
3"P3E_CPU0_PE2_SS_C_TXN<7:0>";
4"P3E_CPU0_PE2_SS_RXN<7:0>";
5"P3E_CPU0_PE1_SS_R_RXN<7:0>";
6"P3E_CPU0_PE2_SS_RXP<7:0>";
7"P3E_CPU0_PE1_SS_R_RXP<7:0>";
8"P3E_CPU0_PE1_SS_C_TXP<7:0>";
9"P3E_CPU0_PE1_PCH_CON_RXP<15:8>";
10"GND\g";
11"GND\g";
12"P3E_CPU0_PE1_SS_C_TXN<0>";
13"P3E_CPU0_PE2_SS_RXP<1>";
14"P3E_CPU0_PE1_SS_R_RXN<1>";
15"P3E_CPU0_PE2_SS_C_TXP<5>";
16"FM_PRSNT_2_6_N";
17"P3E_CPU0_PE2_SS_C_TXP<7>";
18"P3E_CPU0_PE1_SS_R_RXP<7>";
19"P3E_CPU0_PE2_SS_C_TXP<6>";
20"P3E_CPU0_PE2_SS_C_TXN<6>";
21"P3E_CPU0_PE2_SS_C_TXN<5>";
22"P3E_CPU0_PE2_SS_C_TXN<4>";
23"P3E_CPU0_PE2_SS_C_TXN<3>";
24"P3E_CPU0_PE2_SS_C_TXP<2>";
25"P3E_CPU0_PE2_SS_C_TXN<2>";
26"P3E_CPU0_PE2_SS_C_TXP<1>";
27"P3E_CPU0_PE2_SS_C_TXN<0>";
28"P3E_CPU0_PE1_SS_C_TXP<0>";
29"P3E_CPU0_PE1_SS_C_TXP<1>";
30"P3E_CPU0_PE2_SS_RXN<5>";
31"P3E_CPU0_PE2_SS_RXP<3>";
32"P3E_CPU0_PE2_SS_RXP<2>";
33"P3E_CPU0_PE2_SS_RXN<1>";
34"P3E_CPU0_PE2_SS_RXN<7>";
35"P3E_CPU0_PE2_SS_RXN<6>";
36"P3E_CPU0_PE2_SS_RXP<6>";
37"P3E_CPU0_PE2_SS_RXP<5>";
38"P3E_CPU0_PE1_SS_R_RXP<2>";
39"P3E_CPU0_PE2_SS_RXP<0>";
40"P3E_CPU0_PE2_SS_RXN<4>";
41"P3E_CPU0_PE2_SS_RXP<7>";
42"P3E_CPU0_PE2_SS_RXN<0>";
43"P3E_CPU0_PE1_SS_R_RXP<5>";
44"P3E_CPU0_PE1_SS_R_RXP<6>";
45"P3E_CPU0_PE1_SS_R_RXP<4>";
46"P3E_CPU0_PE1_SS_R_RXP<3>";
47"P3E_CPU0_PE1_SS_R_RXN<7>";
48"P3E_CPU0_PE1_PCH_CON_RXP<8>";
49"P3E_CPU0_PE1_SS_R_RXN<6>";
50"P3E_CPU0_PE1_SS_R_RXN<5>";
51"P3E_CPU0_PE1_SS_R_RXN<2>";
52"P3E_CPU0_PE1_SS_R_RXN<4>";
53"P3E_CPU0_PE1_SS_R_RXN<3>";
54"P3E_CPU0_PE1_SS_C_TXP<2>";
55"P3E_CPU0_PE1_SS_C_TXP<3>";
56"P3E_CPU0_PE1_SS_C_TXP<4>";
57"P3E_CPU0_PE1_SS_C_TXP<5>";
58"P3E_CPU0_PE1_SS_C_TXP<6>";
59"P3E_CPU0_PE1_SS_C_TXP<7>";
60"P3E_CPU0_PE1_SS_C_TXN<2>";
61"P3E_CPU0_PE1_SS_C_TXN<3>";
62"P3E_CPU0_PE1_SS_C_TXN<4>";
63"P3E_CPU0_PE1_SS_C_TXN<5>";
64"P3E_CPU0_PE1_SS_C_TXN<6>";
65"P3E_CPU0_PE1_SS_C_TXN<7>";
66"P3E_CPU0_PE1_SS_R_RXP<1>";
67"P3E_CPU0_PE1_SS_R_RXP<0>";
68"P3E_CPU0_PE2_SS_RXP<4>";
69"P3E_CPU0_PE1_SS_R_RXN<0>";
70"P3E_CPU0_PE2_SS_RXN<2>";
71"P3E_CPU0_PE2_SS_RXN<3>";
72"P3E_CPU0_PE2_SS_C_TXN<7>";
73"P3E_CPU0_PE2_SS_C_TXN<1>";
74"P3E_CPU0_PE2_SS_C_TXP<4>";
75"P3E_CPU0_PE2_SS_C_TXP<3>";
76"P3E_CPU0_PE2_SS_C_TXP<0>";
77"P3E_CPU0_PE1_SS_C_TXN<1>";
%"TAP"
"1","(-2025,2350)","2","mstr_standard","I10";
;
CDS_LIB"mstr_standard"
BODY_TYPE"PLUMBING"
HDL_TAP"TRUE";
"B \NAC \NWC"2;
"S \NAC"
BN"5"15;
%"TAP"
"1","(-2275,2400)","2","mstr_standard","I11";
;
CDS_LIB"mstr_standard"
BODY_TYPE"PLUMBING"
HDL_TAP"TRUE";
"B \NAC \NWC"3;
"S \NAC"
BN"5"21;
%"TAP"
"1","(-2275,2550)","2","mstr_standard","I12";
;
CDS_LIB"mstr_standard"
BODY_TYPE"PLUMBING"
HDL_TAP"TRUE";
"B \NAC \NWC"3;
"S \NAC"
BN"4"22;
%"TAP"
"1","(-2275,2700)","2","mstr_standard","I13";
;
CDS_LIB"mstr_standard"
BODY_TYPE"PLUMBING"
HDL_TAP"TRUE";
"B \NAC \NWC"3;
"S \NAC"
BN"3"23;
%"TAP"
"1","(-2275,2850)","2","mstr_standard","I14";
;
CDS_LIB"mstr_standard"
BODY_TYPE"PLUMBING"
HDL_TAP"TRUE";
"B \NAC \NWC"3;
"S \NAC"
BN"2"25;
%"TAP"
"1","(-2275,2950)","2","mstr_standard","I15";
;
CDS_LIB"mstr_standard"
BODY_TYPE"PLUMBING"
HDL_TAP"TRUE";
"B \NAC \NWC"3;
"S \NAC"
BN"1"73;
%"TAP"
"1","(-2275,3150)","2","mstr_standard","I16";
;
CDS_LIB"mstr_standard"
BODY_TYPE"PLUMBING"
HDL_TAP"TRUE";
"B \NAC \NWC"3;
"S \NAC"
BN"0"27;
%"TAP"
"1","(-2275,3250)","2","mstr_standard","I17";
;
CDS_LIB"mstr_standard"
BODY_TYPE"PLUMBING"
HDL_TAP"TRUE";
"B \NAC \NWC"8;
"S \NAC"
BN"0"28;
%"TAP"
"1","(-2025,2650)","2","mstr_standard","I18";
;
CDS_LIB"mstr_standard"
BODY_TYPE"PLUMBING"
HDL_TAP"TRUE";
"B \NAC \NWC"2;
"S \NAC"
BN"3"75;
%"TAP"
"1","(-2025,2500)","2","mstr_standard","I19";
;
CDS_LIB"mstr_standard"
BODY_TYPE"PLUMBING"
HDL_TAP"TRUE";
"B \NAC \NWC"2;
"S \NAC"
BN"4"74;
%"TAP"
"1","(-2025,2800)","2","mstr_standard","I20";
;
CDS_LIB"mstr_standard"
BODY_TYPE"PLUMBING"
HDL_TAP"TRUE";
"B \NAC \NWC"2;
"S \NAC"
BN"2"24;
%"TAP"
"1","(-2025,3000)","2","mstr_standard","I21";
;
CDS_LIB"mstr_standard"
BODY_TYPE"PLUMBING"
HDL_TAP"TRUE";
"B \NAC \NWC"2;
"S \NAC"
BN"1"26;
%"TAP"
"1","(-2025,3100)","2","mstr_standard","I22";
;
CDS_LIB"mstr_standard"
BODY_TYPE"PLUMBING"
HDL_TAP"TRUE";
"B \NAC \NWC"2;
"S \NAC"
BN"0"76;
%"TAP"
"1","(-2025,3300)","2","mstr_standard","I23";
;
CDS_LIB"mstr_standard"
BODY_TYPE"PLUMBING"
HDL_TAP"TRUE";
"B \NAC \NWC"1;
"S \NAC"
BN"0"12;
%"TAP"
"1","(-2025,3400)","2","mstr_standard","I24";
;
CDS_LIB"mstr_standard"
BODY_TYPE"PLUMBING"
HDL_TAP"TRUE";
"B \NAC \NWC"1;
"S \NAC"
BN"1"77;
%"GND"
"1","(-1500,1700)","0","mstr_symbols","I25";
;
SIZE"1B"
CDS_LIB"mstr_symbols"
VOLTAGE"0"
HDL_POWER"GND"
BODY_TYPE"PLUMBING";
"A\NAC"10;
%"GND"
"1","(-450,1700)","0","mstr_symbols","I26";
;
CDS_LIB"mstr_symbols"
SIZE"1B"
VOLTAGE"0"
HDL_POWER"GND"
BODY_TYPE"PLUMBING";
"A\NAC"11;
%"TAP"
"1","(-250,2050)","0","mstr_standard","I27";
;
CDS_LIB"mstr_standard"
BODY_TYPE"PLUMBING"
HDL_TAP"TRUE";
"B \NAC \NWC"4;
"S \NAC"
BN"7"34;
%"TAP"
"1","(-250,2350)","0","mstr_standard","I28";
;
CDS_LIB"mstr_standard"
BODY_TYPE"PLUMBING"
HDL_TAP"TRUE";
"B \NAC \NWC"4;
"S \NAC"
BN"5"30;
%"TAP"
"1","(-250,2150)","0","mstr_standard","I29";
;
CDS_LIB"mstr_standard"
BODY_TYPE"PLUMBING"
HDL_TAP"TRUE";
"B \NAC \NWC"4;
"S \NAC"
BN"6"35;
%"TAP"
"1","(-25,2000)","0","mstr_standard","I30";
;
CDS_LIB"mstr_standard"
BODY_TYPE"PLUMBING"
HDL_TAP"TRUE";
"B \NAC \NWC"6;
"S \NAC"
BN"7"41;
%"TAP"
"1","(-25,2300)","0","mstr_standard","I31";
;
CDS_LIB"mstr_standard"
BODY_TYPE"PLUMBING"
HDL_TAP"TRUE";
"B \NAC \NWC"6;
"S \NAC"
BN"5"37;
%"TAP"
"1","(-25,2200)","0","mstr_standard","I32";
;
CDS_LIB"mstr_standard"
BODY_TYPE"PLUMBING"
HDL_TAP"TRUE";
"B \NAC \NWC"6;
"S \NAC"
BN"6"36;
%"TAP"
"1","(-250,2500)","0","mstr_standard","I33";
;
CDS_LIB"mstr_standard"
BODY_TYPE"PLUMBING"
HDL_TAP"TRUE";
"B \NAC \NWC"4;
"S \NAC"
BN"4"40;
%"TAP"
"1","(-250,2650)","0","mstr_standard","I34";
;
CDS_LIB"mstr_standard"
BODY_TYPE"PLUMBING"
HDL_TAP"TRUE";
"B \NAC \NWC"4;
"S \NAC"
BN"3"71;
%"TAP"
"1","(-250,2750)","0","mstr_standard","I35";
;
CDS_LIB"mstr_standard"
BODY_TYPE"PLUMBING"
HDL_TAP"TRUE";
"B \NAC \NWC"4;
"S \NAC"
BN"2"70;
%"TAP"
"1","(-250,3100)","0","mstr_standard","I36";
;
CDS_LIB"mstr_standard"
BODY_TYPE"PLUMBING"
HDL_TAP"TRUE";
"B \NAC \NWC"4;
"S \NAC"
BN"0"42;
%"TAP"
"1","(-250,3250)","0","mstr_standard","I37";
;
CDS_LIB"mstr_standard"
BODY_TYPE"PLUMBING"
HDL_TAP"TRUE";
"B \NAC \NWC"5;
"S \NAC"
BN"0"69;
%"TAP"
"1","(-250,3400)","0","mstr_standard","I38";
;
CDS_LIB"mstr_standard"
BODY_TYPE"PLUMBING"
HDL_TAP"TRUE";
"B \NAC \NWC"5;
"S \NAC"
BN"1"14;
%"TAP"
"1","(-25,2450)","0","mstr_standard","I39";
;
CDS_LIB"mstr_standard"
BODY_TYPE"PLUMBING"
HDL_TAP"TRUE";
"B \NAC \NWC"6;
"S \NAC"
BN"4"68;
%"TAP"
"1","(-25,2800)","0","mstr_standard","I40";
;
CDS_LIB"mstr_standard"
BODY_TYPE"PLUMBING"
HDL_TAP"TRUE";
"B \NAC \NWC"6;
"S \NAC"
BN"2"32;
%"TAP"
"1","(-25,2900)","0","mstr_standard","I41";
;
CDS_LIB"mstr_standard"
BODY_TYPE"PLUMBING"
HDL_TAP"TRUE";
"B \NAC \NWC"6;
"S \NAC"
BN"1"13;
%"TAP"
"1","(-25,3050)","0","mstr_standard","I42";
;
CDS_LIB"mstr_standard"
BODY_TYPE"PLUMBING"
HDL_TAP"TRUE";
"B \NAC \NWC"6;
"S \NAC"
BN"0"39;
%"TAP"
"1","(-25,3350)","0","mstr_standard","I43";
;
CDS_LIB"mstr_standard"
BODY_TYPE"PLUMBING"
HDL_TAP"TRUE";
"B \NAC \NWC"7;
"S \NAC"
BN"1"66;
%"TAP"
"1","(-25,3200)","0","mstr_standard","I44";
;
CDS_LIB"mstr_standard"
BODY_TYPE"PLUMBING"
HDL_TAP"TRUE";
"B \NAC \NWC"7;
"S \NAC"
BN"0"67;
%"TAP"
"1","(-2275,3450)","2","mstr_standard","I47";
;
CDS_LIB"mstr_standard"
BODY_TYPE"PLUMBING"
HDL_TAP"TRUE";
"B \NAC \NWC"8;
"S \NAC"
BN"1"29;
%"TAP"
"1","(-2275,3550)","2","mstr_standard","I48";
;
CDS_LIB"mstr_standard"
BODY_TYPE"PLUMBING"
HDL_TAP"TRUE";
"B \NAC \NWC"8;
"S \NAC"
BN"2"54;
%"TAP"
"1","(-2275,3900)","2","mstr_standard","I49";
;
CDS_LIB"mstr_standard"
BODY_TYPE"PLUMBING"
HDL_TAP"TRUE";
"B \NAC \NWC"8;
"S \NAC"
BN"4"56;
%"TAP"
"1","(-2275,3700)","2","mstr_standard","I50";
;
CDS_LIB"mstr_standard"
BODY_TYPE"PLUMBING"
HDL_TAP"TRUE";
"B \NAC \NWC"8;
"S \NAC"
BN"3"55;
%"TAP"
"1","(-2275,4000)","2","mstr_standard","I51";
;
CDS_LIB"mstr_standard"
BODY_TYPE"PLUMBING"
HDL_TAP"TRUE";
"B \NAC \NWC"8;
"S \NAC"
BN"5"57;
%"TAP"
"1","(-2275,4150)","2","mstr_standard","I52";
;
CDS_LIB"mstr_standard"
BODY_TYPE"PLUMBING"
HDL_TAP"TRUE";
"B \NAC \NWC"8;
"S \NAC"
BN"6"58;
%"TAP"
"1","(-2275,4300)","2","mstr_standard","I53";
;
CDS_LIB"mstr_standard"
BODY_TYPE"PLUMBING"
HDL_TAP"TRUE";
"B \NAC \NWC"8;
"S \NAC"
BN"7"59;
%"TAP"
"1","(-2025,3600)","2","mstr_standard","I54";
;
CDS_LIB"mstr_standard"
BODY_TYPE"PLUMBING"
HDL_TAP"TRUE";
"B \NAC \NWC"1;
"S \NAC"
BN"2"60;
%"TAP"
"1","(-2025,3750)","2","mstr_standard","I55";
;
CDS_LIB"mstr_standard"
BODY_TYPE"PLUMBING"
HDL_TAP"TRUE";
"B \NAC \NWC"1;
"S \NAC"
BN"3"61;
%"TAP"
"1","(-2025,3850)","2","mstr_standard","I56";
;
CDS_LIB"mstr_standard"
BODY_TYPE"PLUMBING"
HDL_TAP"TRUE";
"B \NAC \NWC"1;
"S \NAC"
BN"4"62;
%"TAP"
"1","(-2025,4050)","2","mstr_standard","I57";
;
CDS_LIB"mstr_standard"
BODY_TYPE"PLUMBING"
HDL_TAP"TRUE";
"B \NAC \NWC"1;
"S \NAC"
BN"5"63;
%"TAP"
"1","(-2025,4200)","2","mstr_standard","I58";
;
CDS_LIB"mstr_standard"
BODY_TYPE"PLUMBING"
HDL_TAP"TRUE";
"B \NAC \NWC"1;
"S \NAC"
BN"6"64;
%"TAP"
"1","(-2025,4350)","2","mstr_standard","I59";
;
CDS_LIB"mstr_standard"
BODY_TYPE"PLUMBING"
HDL_TAP"TRUE";
"B \NAC \NWC"1;
"S \NAC"
BN"7"65;
%"TAP"
"1","(-2275,2100)","2","mstr_standard","I6";
;
CDS_LIB"mstr_standard"
BODY_TYPE"PLUMBING"
HDL_TAP"TRUE";
"B \NAC \NWC"3;
"S \NAC"
BN"7"72;
%"TAP"
"1","(-250,3500)","0","mstr_standard","I60";
;
CDS_LIB"mstr_standard"
BODY_TYPE"PLUMBING"
HDL_TAP"TRUE";
"B \NAC \NWC"5;
"S \NAC"
BN"2"51;
%"TAP"
"1","(-250,3700)","0","mstr_standard","I61";
;
CDS_LIB"mstr_standard"
BODY_TYPE"PLUMBING"
HDL_TAP"TRUE";
"B \NAC \NWC"5;
"S \NAC"
BN"3"53;
%"TAP"
"1","(-250,3850)","0","mstr_standard","I62";
;
CDS_LIB"mstr_standard"
BODY_TYPE"PLUMBING"
HDL_TAP"TRUE";
"B \NAC \NWC"5;
"S \NAC"
BN"4"52;
%"TAP"
"1","(-250,4000)","0","mstr_standard","I63";
;
CDS_LIB"mstr_standard"
BODY_TYPE"PLUMBING"
HDL_TAP"TRUE";
"B \NAC \NWC"5;
"S \NAC"
BN"5"50;
%"TAP"
"1","(-250,4150)","0","mstr_standard","I64";
;
CDS_LIB"mstr_standard"
BODY_TYPE"PLUMBING"
HDL_TAP"TRUE";
"B \NAC \NWC"5;
"S \NAC"
BN"6"49;
%"TAP"
"1","(-250,4300)","0","mstr_standard","I65";
;
CDS_LIB"mstr_standard"
BODY_TYPE"PLUMBING"
HDL_TAP"TRUE";
"B \NAC \NWC"5;
"S \NAC"
BN"7"47;
%"TAP"
"1","(-250,4400)","0","mstr_standard","I66";
;
CDS_LIB"mstr_standard"
BODY_TYPE"PLUMBING"
HDL_TAP"TRUE";
"B \NAC \NWC"9;
"S \NAC"
BN"8"48;
%"TAP"
"1","(-25,3650)","0","mstr_standard","I67";
;
CDS_LIB"mstr_standard"
BODY_TYPE"PLUMBING"
HDL_TAP"TRUE";
"B \NAC \NWC"7;
"S \NAC"
BN"3"46;
%"TAP"
"1","(-25,3550)","0","mstr_standard","I68";
;
CDS_LIB"mstr_standard"
BODY_TYPE"PLUMBING"
HDL_TAP"TRUE";
"B \NAC \NWC"7;
"S \NAC"
BN"2"38;
%"TAP"
"1","(-25,3800)","0","mstr_standard","I69";
;
CDS_LIB"mstr_standard"
BODY_TYPE"PLUMBING"
HDL_TAP"TRUE";
"B \NAC \NWC"7;
"S \NAC"
BN"4"45;
%"TAP"
"1","(-2275,2250)","2","mstr_standard","I7";
;
CDS_LIB"mstr_standard"
BODY_TYPE"PLUMBING"
HDL_TAP"TRUE";
"B \NAC \NWC"3;
"S \NAC"
BN"6"20;
%"TAP"
"1","(-25,3950)","0","mstr_standard","I70";
;
CDS_LIB"mstr_standard"
BODY_TYPE"PLUMBING"
HDL_TAP"TRUE";
"B \NAC \NWC"7;
"S \NAC"
BN"5"43;
%"TAP"
"1","(-25,4100)","0","mstr_standard","I71";
;
CDS_LIB"mstr_standard"
BODY_TYPE"PLUMBING"
HDL_TAP"TRUE";
"B \NAC \NWC"7;
"S \NAC"
BN"6"44;
%"TAP"
"1","(-25,4250)","0","mstr_standard","I72";
;
CDS_LIB"mstr_standard"
BODY_TYPE"PLUMBING"
HDL_TAP"TRUE";
"B \NAC \NWC"7;
"S \NAC"
BN"7"18;
%"TAP"
"1","(-25,2600)","0","mstr_standard","I76";
;
CDS_LIB"mstr_standard"
BODY_TYPE"PLUMBING"
HDL_TAP"TRUE";
"B \NAC \NWC"6;
"S \NAC"
BN"3"31;
%"TAP"
"1","(-250,2950)","0","mstr_standard","I77";
;
CDS_LIB"mstr_standard"
BODY_TYPE"PLUMBING"
HDL_TAP"TRUE";
"B \NAC \NWC"4;
"S \NAC"
BN"1"33;
%"SCONN200_H68296001"
"2","(-975,3200)","0","mstr_sconn","I78";
;
CDS_SEC"2"
CDS_LOCATION"J8G1"
SEC"2"
CDS_LMAN_SYM_OUTLINE"-300,1350,300,-1350"
CDS_LIB"mstr_sconn"
SEC_TYPE"SM"
ROOM"IO_SLOT"
PACK_TYPE"SM"
MATERIAL"CONN"
LOCATION"J8G1"
PART_NUMBER"H68296-001";
"IO102"
$PN"102"48;
"IO110"
$PN"110"11;
"IO119"
$PN"119"10;
"IO117"
$PN"117"57;
"IO115"
$PN"115"63;
"IO113"
$PN"113"10;
"IO111"
$PN"111"58;
"IO109"
$PN"109"64;
"IO103"
$PN"103"65;
"IO114"
$PN"114"44;
"IO104"
$PN"104"11;
"IO106"
$PN"106"47;
"IO108"
$PN"108"18;
"IO112"
$PN"112"49;
"IO116"
$PN"116"11;
"IO118"
$PN"118"50;
"IO120"
$PN"120"43;
"IO121"
$PN"121"56;
"IO122"
$PN"122"11;
"IO123"
$PN"123"62;
"IO124"
$PN"124"52;
"IO125"
$PN"125"10;
"IO126"
$PN"126"45;
"IO127"
$PN"127"61;
"IO128"
$PN"128"11;
"IO129"
$PN"129"55;
"IO130"
$PN"130"53;
"IO131"
$PN"131"10;
"IO132"
$PN"132"46;
"IO133"
$PN"133"60;
"IO134"
$PN"134"11;
"IO135"
$PN"135"54;
"IO136"
$PN"136"38;
"IO137"
$PN"137"10;
"IO138"
$PN"138"51;
"IO139"
$PN"139"29;
"IO140"
$PN"140"11;
"IO141"
$PN"141"77;
"IO142"
$PN"142"14;
"IO143"
$PN"143"10;
"IO144"
$PN"144"66;
"IO145"
$PN"145"12;
"IO146"
$PN"146"11;
"IO147"
$PN"147"28;
"IO148"
$PN"148"69;
"IO149"
$PN"149"10;
"IO150"
$PN"150"67;
"IO151"
$PN"151"27;
"IO152"
$PN"152"11;
"IO153"
$PN"153"76;
"IO154"
$PN"154"42;
"IO155"
$PN"155"10;
"IO156"
$PN"156"39;
"IO157"
$PN"157"26;
"IO158"
$PN"158"11;
"IO159"
$PN"159"73;
"IO160"
$PN"160"33;
"IO161"
$PN"161"10;
"IO162"
$PN"162"13;
"IO163"
$PN"163"25;
"IO164"
$PN"164"11;
"IO165"
$PN"165"24;
"IO166"
$PN"166"32;
"IO167"
$PN"167"10;
"IO168"
$PN"168"70;
"IO169"
$PN"169"23;
"IO170"
$PN"170"11;
"IO171"
$PN"171"75;
"IO172"
$PN"172"71;
"IO173"
$PN"173"10;
"IO174"
$PN"174"31;
"IO175"
$PN"175"22;
"IO176"
$PN"176"11;
"IO177"
$PN"177"74;
"IO178"
$PN"178"40;
"IO179"
$PN"179"10;
"IO180"
$PN"180"68;
"IO181"
$PN"181"21;
"IO182"
$PN"182"11;
"IO183"
$PN"183"15;
"IO184"
$PN"184"30;
"IO185"
$PN"185"10;
"IO186"
$PN"186"37;
"IO187"
$PN"187"20;
"IO188"
$PN"188"11;
"IO189"
$PN"189"19;
"IO190"
$PN"190"36;
"IO191"
$PN"191"10;
"IO192"
$PN"192"35;
"IO193"
$PN"193"72;
"IO194"
$PN"194"11;
"IO195"
$PN"195"17;
"IO196"
$PN"196"34;
"IO197"
$PN"197"10;
"IO198"
$PN"198"41;
"IO199"
$PN"199"16;
"IO200"
$PN"200"11;
"IO101"
$PN"101"10;
"IO105"
$PN"105"59;
"IO107"
$PN"107"10;
%"TAP"
"1","(-2025,2050)","2","mstr_standard","I8";
;
CDS_LIB"mstr_standard"
BODY_TYPE"PLUMBING"
HDL_TAP"TRUE";
"B \NAC \NWC"2;
"S \NAC"
BN"7"17;
%"TAP"
"1","(-2025,2200)","2","mstr_standard","I9";
;
CDS_LIB"mstr_standard"
BODY_TYPE"PLUMBING"
HDL_TAP"TRUE";
"B \NAC \NWC"2;
"S \NAC"
BN"6"19;
END.
